DEVICE-TYPE           GERBER_RS274X
OUTPUT-UNITS          INCHES
FILM-SIZE             2400000 1600000
FORMAT                3.5
ABORT-ON-ERROR        NO
SCALE                 1
SUPPRESS-LEAD-ZEROES  YES
SUPPRESS-TRAIL-ZEROES NO
SUPPRESS-EQUAL        YES
UNDEF-APT-CONT        NO
